(kicad_pcb
	(version 20260206)
	(generator "pcbnew")
	(generator_version "10.0")
	(general
		(thickness 1.6)
		(legacy_teardrops no)
	)
	(paper "A4")
	(title_block
		(title "pdpb — Lightning_PDPB_BRD.brd")
		(comment 1 "Lightning (Wiwynn / Facebook NVMe JBOF) / footprints 79-82 of 1140")
	)
	(layers
		(0 "F.Cu" signal "TOP")
		(4 "In1.Cu" signal "L2GND")
		(6 "In2.Cu" signal "L3")
		(8 "In3.Cu" signal "L4VCC")
		(10 "In4.Cu" signal "L5VCC")
		(12 "In5.Cu" signal "L6")
		(14 "In6.Cu" signal "L7GND")
		(2 "B.Cu" signal "BOTTOM")
		(9 "F.Adhes" user "F.Adhesive")
		(11 "B.Adhes" user "B.Adhesive")
		(13 "F.Paste" user "Package Geometry/Pastemask Top")
		(15 "B.Paste" user "Package Geometry/Pastemask Bottom")
		(5 "F.SilkS" user "Ref Des/Silkscreen Top")
		(7 "B.SilkS" user "Ref Des/Silkscreen Bottom")
		(1 "F.Mask" user "Board Geometry/Soldermask Top")
		(3 "B.Mask" user "Board Geometry/Soldermask Bottom")
		(17 "Dwgs.User" user "User.Drawings")
		(19 "Cmts.User" user "User.Comments")
		(21 "Eco1.User" user "User.Eco1")
		(23 "Eco2.User" user "User.Eco2")
		(25 "Edge.Cuts" user "Board Geometry/Outline")
		(27 "Margin" user)
		(31 "F.CrtYd" user "Package Geometry/Place Bound Top")
		(29 "B.CrtYd" user "Package Geometry/Place Bound Bottom")
		(35 "F.Fab" user "Ref Des/Assembly Top")
		(33 "B.Fab" user "Ref Des/Assembly Bottom")
	)
	(footprint ""
		(layer "F.Cu")
		(at 213.3981 -300.5201 180)
		(property "Reference" "R9794"
			(at 0 0 180)
			(layer "F.SilkS")
			(hide yes)
			(effects
				(font
					(size 1.27 1.27)
				)
			)
		)
		(property "Value" "47KR2J-2-GP"
			(at 0.064008 -3.993896 180)
			(unlocked yes)
			(layer "F.Fab")
			(hide yes)
			(effects
				(font
					(size 1.016 1.016)
					(thickness 0.1524)
				)
			)
		)
		(property "Device Type" "R402H16"
			(at 0.064008 -5.517896 180)
			(unlocked yes)
			(layer "F.Fab")
			(hide yes)
			(effects
				(font
					(size 1.016 1.016)
					(thickness 0.1524)
				)
			)
		)
		(duplicate_pad_numbers_are_jumpers no)
		(fp_line
			(start 0.508 -0.9398)
			(end -0.508 -0.9398)
			(stroke
				(width 0.1524)
				(type default)
			)
			(layer "F.SilkS")
		)
		(fp_line
			(start -0.508 -0.9398)
			(end -0.508 0.9398)
			(stroke
				(width 0.1524)
				(type default)
			)
			(layer "F.SilkS")
		)
		(fp_rect
			(start -0.508 0.9398)
			(end 0.508 -0.9398)
			(stroke
				(width 0)
				(type default)
			)
			(fill no)
			(layer "F.CrtYd")
		)
		(fp_rect
			(start -0.508 0.9398)
			(end 0.508 -0.9398)
			(stroke
				(width 0)
				(type default)
			)
			(fill no)
			(layer "F.Fab")
		)
		(pad "1" smd custom
			(at 0 -0.4445 180)
			(size 0.1397 0.1397)
			(layers "F.Cu" "F.Mask" "F.Paste")
			(net "P12V")
			(options
				(clearance outline)
				(anchor circle)
			)
			(primitives
				(gr_poly
					(pts
						(arc
							(start -0.1778 -0.2794)
							(mid -0.249642 -0.249642)
							(end -0.2794 -0.1778)
						)
						(arc
							(start -0.2794 0.1778)
							(mid -0.249642 0.249642)
							(end -0.1778 0.2794)
						)
						(arc
							(start 0.1778 0.2794)
							(mid 0.249642 0.249642)
							(end 0.2794 0.1778)
						)
						(arc
							(start 0.2794 -0.1778)
							(mid 0.249642 -0.249642)
							(end 0.1778 -0.2794)
						)
					)
					(width 0)
					(fill yes)
				)
			)
		)
		(pad "2" smd custom
			(at 0 0.4445 180)
			(size 0.1397 0.1397)
			(layers "F.Cu" "F.Mask" "F.Paste")
			(net "P12V_MOST2_GATE")
			(options
				(clearance outline)
				(anchor circle)
			)
			(primitives
				(gr_poly
					(pts
						(arc
							(start -0.1778 -0.2794)
							(mid -0.249642 -0.249642)
							(end -0.2794 -0.1778)
						)
						(arc
							(start -0.2794 0.1778)
							(mid -0.249642 0.249642)
							(end -0.1778 0.2794)
						)
						(arc
							(start 0.1778 0.2794)
							(mid 0.249642 0.249642)
							(end 0.2794 0.1778)
						)
						(arc
							(start 0.2794 -0.1778)
							(mid 0.249642 -0.249642)
							(end 0.1778 -0.2794)
						)
					)
					(width 0)
					(fill yes)
				)
			)
		)
	)
	(footprint ""
		(layer "F.Cu")
		(at 31.877 -142.24)
		(property "Reference" "Q70"
			(at 0 0 0)
			(layer "F.SilkS")
			(hide yes)
			(effects
				(font
					(size 1.27 1.27)
				)
			)
		)
		(property "Value" "2N7002A-7-GP"
			(at 0.127 -8.9662 0)
			(unlocked yes)
			(layer "F.Fab")
			(hide yes)
			(effects
				(font
					(size 1.016 1.016)
					(thickness 0.1524)
				)
			)
		)
		(property "Device Type" "SOT23DGS2D4H48"
			(at 0.127 -10.4902 0)
			(unlocked yes)
			(layer "F.Fab")
			(hide yes)
			(effects
				(font
					(size 1.016 1.016)
					(thickness 0.1524)
				)
			)
		)
		(duplicate_pad_numbers_are_jumpers no)
		(fp_line
			(start -1.651 -1.778)
			(end -1.651 1.778)
			(stroke
				(width 0.1524)
				(type default)
			)
			(layer "F.SilkS")
		)
		(fp_line
			(start -1.651 1.778)
			(end 1.651 1.778)
			(stroke
				(width 0.1524)
				(type default)
			)
			(layer "F.SilkS")
		)
		(fp_line
			(start 1.651 -1.778)
			(end -1.651 -1.778)
			(stroke
				(width 0.1524)
				(type default)
			)
			(layer "F.SilkS")
		)
		(fp_line
			(start 1.651 1.778)
			(end 1.651 -1.778)
			(stroke
				(width 0.1524)
				(type default)
			)
			(layer "F.SilkS")
		)
		(fp_poly
			(pts
				(xy -1.778 1.8796) (xy -1.778 -1.8796) (xy 1.778 -1.8796) (xy 1.778 1.8796)
			)
			(stroke
				(width 0)
				(type default)
			)
			(fill no)
			(layer "F.CrtYd")
		)
		(fp_poly
			(pts
				(xy -1.778 1.8796) (xy -1.778 -1.8796) (xy 1.778 -1.8796) (xy 1.778 1.8796)
			)
			(stroke
				(width 0)
				(type default)
			)
			(fill no)
			(layer "F.Fab")
		)
		(pad "D" smd custom
			(at 0 -0.9525)
			(size 0.1905 0.1905)
			(layers "F.Cu" "F.Mask" "F.Paste")
			(net "ATTN_LED_DR8_MOS_N")
			(options
				(clearance outline)
				(anchor circle)
			)
			(primitives
				(gr_poly
					(pts
						(arc
							(start -0.1778 0.5715)
							(mid -0.321484 0.511984)
							(end -0.381 0.3683)
						)
						(arc
							(start -0.381 -0.3683)
							(mid -0.321484 -0.511984)
							(end -0.1778 -0.5715)
						)
						(arc
							(start 0.1778 -0.5715)
							(mid 0.321484 -0.511984)
							(end 0.381 -0.3683)
						)
						(arc
							(start 0.381 0.3683)
							(mid 0.321484 0.511984)
							(end 0.1778 0.5715)
						)
					)
					(width 0)
					(fill yes)
				)
			)
		)
		(pad "G" smd custom
			(at -0.98425 0.9525)
			(size 0.1905 0.1905)
			(layers "F.Cu" "F.Mask" "F.Paste")
			(net "SSD8_CLK0_OE_MOS_N")
			(options
				(clearance outline)
				(anchor circle)
			)
			(primitives
				(gr_poly
					(pts
						(arc
							(start -0.1778 0.5715)
							(mid -0.321484 0.511984)
							(end -0.381 0.3683)
						)
						(arc
							(start -0.381 -0.3683)
							(mid -0.321484 -0.511984)
							(end -0.1778 -0.5715)
						)
						(arc
							(start 0.1778 -0.5715)
							(mid 0.321484 -0.511984)
							(end 0.381 -0.3683)
						)
						(arc
							(start 0.381 0.3683)
							(mid 0.321484 0.511984)
							(end 0.1778 0.5715)
						)
					)
					(width 0)
					(fill yes)
				)
			)
		)
		(pad "S" smd custom
			(at 0.98425 0.9525)
			(size 0.1905 0.1905)
			(layers "F.Cu" "F.Mask" "F.Paste")
			(net "ATTN_LED_DR8_R")
			(options
				(clearance outline)
				(anchor circle)
			)
			(primitives
				(gr_poly
					(pts
						(arc
							(start -0.1778 0.5715)
							(mid -0.321484 0.511984)
							(end -0.381 0.3683)
						)
						(arc
							(start -0.381 -0.3683)
							(mid -0.321484 -0.511984)
							(end -0.1778 -0.5715)
						)
						(arc
							(start 0.1778 -0.5715)
							(mid 0.321484 -0.511984)
							(end 0.381 -0.3683)
						)
						(arc
							(start 0.381 0.3683)
							(mid 0.321484 0.511984)
							(end 0.1778 0.5715)
						)
					)
					(width 0)
					(fill yes)
				)
			)
		)
	)
	(footprint ""
		(layer "F.Cu")
		(at 228.009704 -145.903188 -90)
		(property "Reference" "R9933"
			(at 0 0 270)
			(layer "F.SilkS")
			(hide yes)
			(effects
				(font
					(size 1.27 1.27)
				)
			)
		)
		(property "Value" "4K7R2J-2-GP"
			(at 0.064008 -3.993896 270)
			(unlocked yes)
			(layer "F.Fab")
			(hide yes)
			(effects
				(font
					(size 1.016 1.016)
					(thickness 0.1524)
				)
			)
		)
		(property "Device Type" "R402H16"
			(at 0.064008 -5.517896 270)
			(unlocked yes)
			(layer "F.Fab")
			(hide yes)
			(effects
				(font
					(size 1.016 1.016)
					(thickness 0.1524)
				)
			)
		)
		(duplicate_pad_numbers_are_jumpers no)
		(fp_line
			(start -0.508 -0.9398)
			(end -0.508 0.9398)
			(stroke
				(width 0.1524)
				(type default)
			)
			(layer "F.SilkS")
		)
		(fp_line
			(start 0.508 -0.9398)
			(end -0.508 -0.9398)
			(stroke
				(width 0.1524)
				(type default)
			)
			(layer "F.SilkS")
		)
		(fp_rect
			(start -0.508 0.9398)
			(end 0.508 -0.9398)
			(stroke
				(width 0)
				(type default)
			)
			(fill no)
			(layer "F.CrtYd")
		)
		(fp_rect
			(start -0.508 0.9398)
			(end 0.508 -0.9398)
			(stroke
				(width 0)
				(type default)
			)
			(fill no)
			(layer "F.Fab")
		)
		(pad "1" smd custom
			(at 0 -0.4445 270)
			(size 0.1397 0.1397)
			(layers "F.Cu" "F.Mask" "F.Paste")
			(net "P3V3")
			(options
				(clearance outline)
				(anchor circle)
			)
			(primitives
				(gr_poly
					(pts
						(arc
							(start -0.1778 -0.2794)
							(mid -0.249642 -0.249642)
							(end -0.2794 -0.1778)
						)
						(arc
							(start -0.2794 0.1778)
							(mid -0.249642 0.249642)
							(end -0.1778 0.2794)
						)
						(arc
							(start 0.1778 0.2794)
							(mid 0.249642 0.249642)
							(end 0.2794 0.1778)
						)
						(arc
							(start 0.2794 -0.1778)
							(mid 0.249642 -0.249642)
							(end 0.1778 -0.2794)
						)
					)
					(width 0)
					(fill yes)
				)
			)
		)
		(pad "2" smd custom
			(at 0 0.4445 270)
			(size 0.1397 0.1397)
			(layers "F.Cu" "F.Mask" "F.Paste")
			(net "ATTN_LED_DR3_MOS_N")
			(options
				(clearance outline)
				(anchor circle)
			)
			(primitives
				(gr_poly
					(pts
						(arc
							(start -0.1778 -0.2794)
							(mid -0.249642 -0.249642)
							(end -0.2794 -0.1778)
						)
						(arc
							(start -0.2794 0.1778)
							(mid -0.249642 0.249642)
							(end -0.1778 0.2794)
						)
						(arc
							(start 0.1778 0.2794)
							(mid 0.249642 0.249642)
							(end 0.2794 0.1778)
						)
						(arc
							(start 0.2794 -0.1778)
							(mid 0.249642 -0.249642)
							(end 0.1778 -0.2794)
						)
					)
					(width 0)
					(fill yes)
				)
			)
		)
	)
	(footprint ""
		(layer "F.Cu")
		(at 22.247606 -368.1095 180)
		(property "Reference" "R9854"
			(at 0 0 180)
			(layer "F.SilkS")
			(hide yes)
			(effects
				(font
					(size 1.27 1.27)
				)
			)
		)
		(property "Value" "0R2J-2-GP"
			(at 0.064008 -3.993896 180)
			(unlocked yes)
			(layer "F.Fab")
			(hide yes)
			(effects
				(font
					(size 1.016 1.016)
					(thickness 0.1524)
				)
			)
		)
		(property "Device Type" "R402H16"
			(at 0.064008 -5.517896 180)
			(unlocked yes)
			(layer "F.Fab")
			(hide yes)
			(effects
				(font
					(size 1.016 1.016)
					(thickness 0.1524)
				)
			)
		)
		(duplicate_pad_numbers_are_jumpers no)
		(fp_line
			(start 0.508 -0.9398)
			(end -0.508 -0.9398)
			(stroke
				(width 0.1524)
				(type default)
			)
			(layer "F.SilkS")
		)
		(fp_line
			(start -0.508 -0.9398)
			(end -0.508 0.9398)
			(stroke
				(width 0.1524)
				(type default)
			)
			(layer "F.SilkS")
		)
		(fp_rect
			(start -0.508 0.9398)
			(end 0.508 -0.9398)
			(stroke
				(width 0)
				(type default)
			)
			(fill no)
			(layer "F.CrtYd")
		)
		(fp_rect
			(start -0.508 0.9398)
			(end 0.508 -0.9398)
			(stroke
				(width 0)
				(type default)
			)
			(fill no)
			(layer "F.Fab")
		)
		(pad "1" smd custom
			(at 0 -0.4445 180)
			(size 0.1397 0.1397)
			(layers "F.Cu" "F.Mask" "F.Paste")
			(net "ATTN_LED_DR11_R")
			(options
				(clearance outline)
				(anchor circle)
			)
			(primitives
				(gr_poly
					(pts
						(arc
							(start -0.1778 -0.2794)
							(mid -0.249642 -0.249642)
							(end -0.2794 -0.1778)
						)
						(arc
							(start -0.2794 0.1778)
							(mid -0.249642 0.249642)
							(end -0.1778 0.2794)
						)
						(arc
							(start 0.1778 0.2794)
							(mid 0.249642 0.249642)
							(end 0.2794 0.1778)
						)
						(arc
							(start 0.2794 -0.1778)
							(mid 0.249642 -0.249642)
							(end 0.1778 -0.2794)
						)
					)
					(width 0)
					(fill yes)
				)
			)
		)
		(pad "2" smd custom
			(at 0 0.4445 180)
			(size 0.1397 0.1397)
			(layers "F.Cu" "F.Mask" "F.Paste")
			(net "ATTN_LED_DR11_N")
			(options
				(clearance outline)
				(anchor circle)
			)
			(primitives
				(gr_poly
					(pts
						(arc
							(start -0.1778 -0.2794)
							(mid -0.249642 -0.249642)
							(end -0.2794 -0.1778)
						)
						(arc
							(start -0.2794 0.1778)
							(mid -0.249642 0.249642)
							(end -0.1778 0.2794)
						)
						(arc
							(start 0.1778 0.2794)
							(mid 0.249642 0.249642)
							(end 0.2794 0.1778)
						)
						(arc
							(start 0.2794 -0.1778)
							(mid 0.249642 -0.249642)
							(end 0.1778 -0.2794)
						)
					)
					(width 0)
					(fill yes)
				)
			)
		)
	)
)
